(kicad_pcb
	(version 20260206)
	(generator "pcbnew")
	(generator_version "10.0")
	(general
		(thickness 1.6)
		(legacy_teardrops no)
	)
	(paper "A4")
	(title_block
		(title "Bryce Canyon_F.DPB_16315-1-OCP.brd")
		(comment 1 "Bryce Canyon / footprints 730-738 of 2223")
	)
	(layers
		(0 "F.Cu" signal "TOP")
		(4 "In1.Cu" signal "L2GND")
		(6 "In2.Cu" signal "L3")
		(8 "In3.Cu" signal "L4GND")
		(10 "In4.Cu" signal "L5")
		(12 "In5.Cu" signal "L6VCC")
		(14 "In6.Cu" signal "L7VCC")
		(16 "In7.Cu" signal "L8")
		(18 "In8.Cu" signal "L9GND")
		(20 "In9.Cu" signal "L10")
		(22 "In10.Cu" signal "L11GND")
		(2 "B.Cu" signal "BOTTOM")
		(9 "F.Adhes" user "F.Adhesive")
		(11 "B.Adhes" user "B.Adhesive")
		(13 "F.Paste" user "Package Geometry/Pastemask Top")
		(15 "B.Paste" user "Package Geometry/Pastemask Bottom")
		(5 "F.SilkS" user "Ref Des/Silkscreen Top")
		(7 "B.SilkS" user "Ref Des/Silkscreen Bottom")
		(1 "F.Mask" user "Board Geometry/Soldermask Top")
		(3 "B.Mask" user "Board Geometry/Soldermask Bottom")
		(17 "Dwgs.User" user "User.Drawings")
		(19 "Cmts.User" user "User.Comments")
		(21 "Eco1.User" user "User.Eco1")
		(23 "Eco2.User" user "User.Eco2")
		(25 "Edge.Cuts" user "Board Geometry/Outline")
		(27 "Margin" user)
		(31 "F.CrtYd" user "Package Geometry/Place Bound Top")
		(29 "B.CrtYd" user "Package Geometry/Place Bound Bottom")
		(35 "F.Fab" user "Ref Des/Assembly Top")
		(33 "B.Fab" user "Ref Des/Assembly Bottom")
	)
	(footprint ""
		(layer "F.Cu")
		(at 368.862102 -162.792918 90)
		(property "Reference" "D19"
			(at 0 0 90)
			(layer "F.SilkS")
			(hide yes)
			(effects
				(font
					(size 1.27 1.27)
				)
			)
		)
		(property "Value" "RB551V30-GP"
			(at 0 -6.7818 90)
			(unlocked yes)
			(layer "F.Fab")
			(hide yes)
			(effects
				(font
					(size 1.016 1.016)
					(thickness 0.1524)
				)
			)
		)
		(property "Device Type" "SOD323AKH38"
			(at 0 -8.6868 90)
			(unlocked yes)
			(layer "F.Fab")
			(hide yes)
			(effects
				(font
					(size 1.016 1.016)
					(thickness 0.1524)
				)
			)
		)
		(duplicate_pad_numbers_are_jumpers no)
		(fp_line
			(start 0.889 -1.9304)
			(end 0.889 2.159)
			(stroke
				(width 0.1524)
				(type default)
			)
			(layer "F.SilkS")
		)
		(fp_line
			(start -0.889 -1.9304)
			(end 0.889 -1.9304)
			(stroke
				(width 0.1524)
				(type default)
			)
			(layer "F.SilkS")
		)
		(fp_line
			(start 0.762 2.0574)
			(end -0.762 2.0574)
			(stroke
				(width 0.508)
				(type default)
			)
			(layer "F.SilkS")
		)
		(fp_line
			(start 0.889 2.159)
			(end -0.889 2.159)
			(stroke
				(width 0.1524)
				(type default)
			)
			(layer "F.SilkS")
		)
		(fp_line
			(start -0.889 2.159)
			(end -0.889 -1.9304)
			(stroke
				(width 0.1524)
				(type default)
			)
			(layer "F.SilkS")
		)
		(fp_rect
			(start -1.016 2.3114)
			(end 1.016 -2.0066)
			(stroke
				(width 0)
				(type default)
			)
			(fill no)
			(layer "F.CrtYd")
		)
		(fp_poly
			(pts
				(xy -1.016 -2.0066) (xy 1.016 -2.0066) (xy 1.016 2.3114) (xy -1.016 2.3114)
			)
			(stroke
				(width 0)
				(type default)
			)
			(fill no)
			(layer "F.Fab")
		)
		(pad "A" smd rect
			(at 0 -1.143 90)
			(size 0.5588 1.016)
			(layers "F.Cu" "F.Mask" "F.Paste")
			(net "SW_HDD_R19")
		)
		(pad "K" smd rect
			(at 0 1.143 90)
			(size 0.5588 1.016)
			(layers "F.Cu" "F.Mask" "F.Paste")
			(net "SW_HDD_N19")
		)
	)
	(footprint ""
		(layer "F.Cu")
		(at 255.309878 -147.079716 -90)
		(property "Reference" "TP224"
			(at 0 0 270)
			(layer "F.SilkS")
			(hide yes)
			(effects
				(font
					(size 1.27 1.27)
				)
			)
		)
		(property "Value" "TPAD32-GP"
			(at -0.0508 -1.6764 270)
			(unlocked yes)
			(layer "F.Fab")
			(hide yes)
			(effects
				(font
					(size 1.016 1.016)
					(thickness 0.1524)
				)
			)
		)
		(property "Device Type" "TPAD32"
			(at -0.0508 -3.2004 270)
			(unlocked yes)
			(layer "F.Fab")
			(hide yes)
			(effects
				(font
					(size 1.016 1.016)
					(thickness 0.1524)
				)
			)
		)
		(duplicate_pad_numbers_are_jumpers no)
		(fp_poly
			(pts
				(arc
					(start 0 -0.4064)
					(mid 0 0.4064)
					(end 0 -0.4064)
				)
			)
			(stroke
				(width 0)
				(type default)
			)
			(fill no)
			(layer "F.CrtYd")
		)
		(fp_poly
			(pts
				(arc
					(start 0 -0.7112)
					(mid 0 0.7112)
					(end 0 -0.7112)
				)
			)
			(stroke
				(width 0)
				(type default)
			)
			(fill no)
			(layer "F.Fab")
		)
		(pad "1" smd circle
			(at 0 0 270)
			(size 0.8128 0.8128)
			(layers "F.Cu" "F.Mask" "F.Paste")
			(net "TP_SMB_COMP_A_NIC_SCL")
		)
	)
	(footprint ""
		(layer "F.Cu")
		(at 257.328924 -140.851128 90)
		(property "Reference" "R18"
			(at 0 0 90)
			(layer "F.SilkS")
			(hide yes)
			(effects
				(font
					(size 1.27 1.27)
				)
			)
		)
		(property "Value" "4K7R2F-GP"
			(at 0.064008 -3.993896 90)
			(unlocked yes)
			(layer "F.Fab")
			(hide yes)
			(effects
				(font
					(size 1.016 1.016)
					(thickness 0.1524)
				)
			)
		)
		(property "Device Type" "R402H16"
			(at 0.064008 -5.517896 90)
			(unlocked yes)
			(layer "F.Fab")
			(hide yes)
			(effects
				(font
					(size 1.016 1.016)
					(thickness 0.1524)
				)
			)
		)
		(duplicate_pad_numbers_are_jumpers no)
		(fp_line
			(start 0.508 -0.9398)
			(end -0.508 -0.9398)
			(stroke
				(width 0.1524)
				(type default)
			)
			(layer "F.SilkS")
		)
		(fp_line
			(start -0.508 -0.9398)
			(end -0.508 0.9398)
			(stroke
				(width 0.1524)
				(type default)
			)
			(layer "F.SilkS")
		)
		(fp_rect
			(start -0.508 0.9398)
			(end 0.508 -0.9398)
			(stroke
				(width 0)
				(type default)
			)
			(fill no)
			(layer "F.CrtYd")
		)
		(fp_rect
			(start -0.508 0.9398)
			(end 0.508 -0.9398)
			(stroke
				(width 0)
				(type default)
			)
			(fill no)
			(layer "F.Fab")
		)
		(pad "1" smd custom
			(at 0 -0.4445 90)
			(size 0.1397 0.1397)
			(layers "F.Cu" "F.Mask" "F.Paste")
			(net "COMP_A_FAST_THROTTLE_N")
			(options
				(clearance outline)
				(anchor circle)
			)
			(primitives
				(gr_poly
					(pts
						(arc
							(start -0.1778 -0.2794)
							(mid -0.249642 -0.249642)
							(end -0.2794 -0.1778)
						)
						(arc
							(start -0.2794 0.1778)
							(mid -0.249642 0.249642)
							(end -0.1778 0.2794)
						)
						(arc
							(start 0.1778 0.2794)
							(mid 0.249642 0.249642)
							(end 0.2794 0.1778)
						)
						(arc
							(start 0.2794 -0.1778)
							(mid 0.249642 -0.249642)
							(end 0.1778 -0.2794)
						)
					)
					(width 0)
					(fill yes)
				)
			)
		)
		(pad "2" smd custom
			(at 0 0.4445 90)
			(size 0.1397 0.1397)
			(layers "F.Cu" "F.Mask" "F.Paste")
			(net "P3V3_STBY_A")
			(options
				(clearance outline)
				(anchor circle)
			)
			(primitives
				(gr_poly
					(pts
						(arc
							(start -0.1778 -0.2794)
							(mid -0.249642 -0.249642)
							(end -0.2794 -0.1778)
						)
						(arc
							(start -0.2794 0.1778)
							(mid -0.249642 0.249642)
							(end -0.1778 0.2794)
						)
						(arc
							(start 0.1778 0.2794)
							(mid 0.249642 0.249642)
							(end 0.2794 0.1778)
						)
						(arc
							(start 0.2794 -0.1778)
							(mid 0.249642 -0.249642)
							(end 0.1778 -0.2794)
						)
					)
					(width 0)
					(fill yes)
				)
			)
		)
	)
	(footprint ""
		(layer "F.Cu")
		(at 77.96657 -17.825466 180)
		(property "Reference" "R42"
			(at 0 0 180)
			(layer "F.SilkS")
			(hide yes)
			(effects
				(font
					(size 1.27 1.27)
				)
			)
		)
		(property "Value" "100KR2F-L1-GP"
			(at 0.064008 -3.993896 180)
			(unlocked yes)
			(layer "F.Fab")
			(hide yes)
			(effects
				(font
					(size 1.016 1.016)
					(thickness 0.1524)
				)
			)
		)
		(property "Device Type" "R402H16"
			(at 0.064008 -5.517896 180)
			(unlocked yes)
			(layer "F.Fab")
			(hide yes)
			(effects
				(font
					(size 1.016 1.016)
					(thickness 0.1524)
				)
			)
		)
		(duplicate_pad_numbers_are_jumpers no)
		(fp_line
			(start 0.508 -0.9398)
			(end -0.508 -0.9398)
			(stroke
				(width 0.1524)
				(type default)
			)
			(layer "F.SilkS")
		)
		(fp_line
			(start -0.508 -0.9398)
			(end -0.508 0.9398)
			(stroke
				(width 0.1524)
				(type default)
			)
			(layer "F.SilkS")
		)
		(fp_rect
			(start -0.508 0.9398)
			(end 0.508 -0.9398)
			(stroke
				(width 0)
				(type default)
			)
			(fill no)
			(layer "F.CrtYd")
		)
		(fp_rect
			(start -0.508 0.9398)
			(end 0.508 -0.9398)
			(stroke
				(width 0)
				(type default)
			)
			(fill no)
			(layer "F.Fab")
		)
		(pad "1" smd custom
			(at 0 -0.4445 180)
			(size 0.1397 0.1397)
			(layers "F.Cu" "F.Mask" "F.Paste")
			(net "P3V3_STBY_A")
			(options
				(clearance outline)
				(anchor circle)
			)
			(primitives
				(gr_poly
					(pts
						(arc
							(start -0.1778 -0.2794)
							(mid -0.249642 -0.249642)
							(end -0.2794 -0.1778)
						)
						(arc
							(start -0.2794 0.1778)
							(mid -0.249642 0.249642)
							(end -0.1778 0.2794)
						)
						(arc
							(start 0.1778 0.2794)
							(mid 0.249642 0.249642)
							(end 0.2794 0.1778)
						)
						(arc
							(start 0.2794 -0.1778)
							(mid 0.249642 -0.249642)
							(end 0.1778 -0.2794)
						)
					)
					(width 0)
					(fill yes)
				)
			)
		)
		(pad "2" smd custom
			(at 0 0.4445 180)
			(size 0.1397 0.1397)
			(layers "F.Cu" "F.Mask" "F.Paste")
			(net "BMC_A_MISC_ALERT_N")
			(options
				(clearance outline)
				(anchor circle)
			)
			(primitives
				(gr_poly
					(pts
						(arc
							(start -0.1778 -0.2794)
							(mid -0.249642 -0.249642)
							(end -0.2794 -0.1778)
						)
						(arc
							(start -0.2794 0.1778)
							(mid -0.249642 0.249642)
							(end -0.1778 0.2794)
						)
						(arc
							(start 0.1778 0.2794)
							(mid 0.249642 0.249642)
							(end 0.2794 0.1778)
						)
						(arc
							(start 0.2794 -0.1778)
							(mid 0.249642 -0.249642)
							(end 0.1778 -0.2794)
						)
					)
					(width 0)
					(fill yes)
				)
			)
		)
	)
	(footprint ""
		(layer "F.Cu")
		(at 333.57185 -299.405294 -90)
		(property "Reference" "R271"
			(at 0 0 270)
			(layer "F.SilkS")
			(hide yes)
			(effects
				(font
					(size 1.27 1.27)
				)
			)
		)
		(property "Value" "2R6F-GP"
			(at -0.0508 -4.8514 270)
			(unlocked yes)
			(layer "F.Fab")
			(hide yes)
			(effects
				(font
					(size 1.016 1.016)
					(thickness 0.1524)
				)
			)
		)
		(property "Device Type" "R1206H26"
			(at 0 -6.3754 270)
			(unlocked yes)
			(layer "F.Fab")
			(hide yes)
			(effects
				(font
					(size 1.016 1.016)
					(thickness 0.1524)
				)
			)
		)
		(duplicate_pad_numbers_are_jumpers no)
		(fp_line
			(start -1.016 2.2352)
			(end -1.016 -2.2352)
			(stroke
				(width 0.1524)
				(type default)
			)
			(layer "F.SilkS")
		)
		(fp_line
			(start 1.016 2.2352)
			(end -1.016 2.2352)
			(stroke
				(width 0.1524)
				(type default)
			)
			(layer "F.SilkS")
		)
		(fp_line
			(start -1.016 -2.2352)
			(end 1.016 -2.2352)
			(stroke
				(width 0.1524)
				(type default)
			)
			(layer "F.SilkS")
		)
		(fp_line
			(start 1.016 -2.2352)
			(end 1.016 2.2352)
			(stroke
				(width 0.1524)
				(type default)
			)
			(layer "F.SilkS")
		)
		(fp_rect
			(start -1.0922 2.3114)
			(end 1.0922 -2.3114)
			(stroke
				(width 0)
				(type default)
			)
			(fill no)
			(layer "F.CrtYd")
		)
		(fp_poly
			(pts
				(xy -1.0922 -2.3114) (xy 1.0922 -2.3114) (xy 1.0922 2.3114) (xy -1.0922 2.3114)
			)
			(stroke
				(width 0)
				(type default)
			)
			(fill no)
			(layer "F.Fab")
		)
		(pad "1" smd rect
			(at 0 -1.397 270)
			(size 1.651 1.27)
			(layers "F.Cu" "F.Mask" "F.Paste")
			(net "P12V_HDD6")
		)
		(pad "2" smd rect
			(at 0 1.397 270)
			(size 1.651 1.27)
			(layers "F.Cu" "F.Mask" "F.Paste")
			(net "12V_PRE_6")
		)
	)
	(footprint ""
		(layer "F.Cu")
		(at 43.999912 -269.999968)
		(property "Reference" ""
			(at 0 0 0)
			(layer "F.SilkS")
			(hide yes)
			(effects
				(font
					(size 1.27 1.27)
				)
			)
		)
		(property "Value" "*"
			(at -6.3373 -0.4572 0)
			(unlocked yes)
			(layer "F.Fab")
			(hide yes)
			(effects
				(font
					(size 1.016 1.016)
					(thickness 0.1524)
				)
			)
		)
		(duplicate_pad_numbers_are_jumpers no)
		(fp_poly
			(pts
				(arc
					(start 5.0673 0)
					(mid -5.0673 0)
					(end 5.0673 0)
				)
			)
			(stroke
				(width 0)
				(type default)
			)
			(fill no)
			(layer "B.CrtYd")
		)
		(fp_poly
			(pts
				(arc
					(start 5.0673 0)
					(mid -5.0673 0)
					(end 5.0673 0)
				)
			)
			(stroke
				(width 0)
				(type default)
			)
			(fill no)
			(layer "F.CrtYd")
		)
		(fp_poly
			(pts
				(arc
					(start 5.0673 0)
					(mid -5.0673 0)
					(end 5.0673 0)
				)
			)
			(stroke
				(width 0)
				(type default)
			)
			(fill no)
			(layer "B.Fab")
		)
		(fp_poly
			(pts
				(arc
					(start 5.0673 0)
					(mid -5.0673 0)
					(end 5.0673 0)
				)
			)
			(stroke
				(width 0)
				(type default)
			)
			(fill no)
			(layer "F.Fab")
		)
		(pad "1" thru_hole circle
			(at 0 0)
			(size 9.525 9.525)
			(drill 3.556)
			(layers "*.Cu" "*.Mask")
			(remove_unused_layers no)
			(net "Net_92")
			(clearance -2.4765)
			(thermal_gap 0.3048)
			(padstack
				(mode front_inner_back)
				(layer "Inner"
					(shape circle)
					(size 3.9624 3.9624)
					(clearance 0.3048)
				)
				(layer "B.Cu"
					(shape circle)
					(size 9.525 9.525)
					(clearance -2.4765)
				)
			)
		)
		(zone
			(layers "F.Cu" "B.Cu" "In1.Cu" "In2.Cu" "In3.Cu" "In4.Cu" "In5.Cu" "In6.Cu"
				"In7.Cu" "In8.Cu" "In9.Cu" "In10.Cu"
			)
			(hatch none 0.5)
			(connect_pads
				(clearance 0)
			)
			(min_thickness 0.25)
			(keepout
				(tracks not_allowed)
				(vias allowed)
				(pads allowed)
				(copperpour not_allowed)
				(footprints allowed)
			)
			(placement
				(enabled no)
				(sheetname "")
			)
			(fill
				(thermal_gap 0.5)
				(thermal_bridge_width 0.5)
				(island_removal_mode 0)
			)
			(polygon
				(pts
					(arc
						(start 48.762412 -269.999968)
						(mid 39.237412 -269.999968)
						(end 48.762412 -269.999968)
					)
				)
			)
		)
	)
	(footprint ""
		(layer "F.Cu")
		(at 396.34795 -157.585918 180)
		(property "Reference" "R598"
			(at 0 0 180)
			(layer "F.SilkS")
			(hide yes)
			(effects
				(font
					(size 1.27 1.27)
				)
			)
		)
		(property "Value" "1KR2F-3-GP"
			(at 0.064008 -3.993896 180)
			(unlocked yes)
			(layer "F.Fab")
			(hide yes)
			(effects
				(font
					(size 1.016 1.016)
					(thickness 0.1524)
				)
			)
		)
		(property "Device Type" "R402H16"
			(at 0.064008 -5.517896 180)
			(unlocked yes)
			(layer "F.Fab")
			(hide yes)
			(effects
				(font
					(size 1.016 1.016)
					(thickness 0.1524)
				)
			)
		)
		(duplicate_pad_numbers_are_jumpers no)
		(fp_line
			(start 0.508 -0.9398)
			(end -0.508 -0.9398)
			(stroke
				(width 0.1524)
				(type default)
			)
			(layer "F.SilkS")
		)
		(fp_line
			(start -0.508 -0.9398)
			(end -0.508 0.9398)
			(stroke
				(width 0.1524)
				(type default)
			)
			(layer "F.SilkS")
		)
		(fp_rect
			(start -0.508 0.9398)
			(end 0.508 -0.9398)
			(stroke
				(width 0)
				(type default)
			)
			(fill no)
			(layer "F.CrtYd")
		)
		(fp_rect
			(start -0.508 0.9398)
			(end 0.508 -0.9398)
			(stroke
				(width 0)
				(type default)
			)
			(fill no)
			(layer "F.Fab")
		)
		(pad "1" smd custom
			(at 0 -0.4445 180)
			(size 0.1397 0.1397)
			(layers "F.Cu" "F.Mask" "F.Paste")
			(net "P3V3_STBY_A")
			(options
				(clearance outline)
				(anchor circle)
			)
			(primitives
				(gr_poly
					(pts
						(arc
							(start -0.1778 -0.2794)
							(mid -0.249642 -0.249642)
							(end -0.2794 -0.1778)
						)
						(arc
							(start -0.2794 0.1778)
							(mid -0.249642 0.249642)
							(end -0.1778 0.2794)
						)
						(arc
							(start 0.1778 0.2794)
							(mid 0.249642 0.249642)
							(end 0.2794 0.1778)
						)
						(arc
							(start 0.2794 -0.1778)
							(mid 0.249642 -0.249642)
							(end 0.1778 -0.2794)
						)
					)
					(width 0)
					(fill yes)
				)
			)
		)
		(pad "2" smd custom
			(at 0 0.4445 180)
			(size 0.1397 0.1397)
			(layers "F.Cu" "F.Mask" "F.Paste")
			(net "SW_PWR_R_HDD20")
			(options
				(clearance outline)
				(anchor circle)
			)
			(primitives
				(gr_poly
					(pts
						(arc
							(start -0.1778 -0.2794)
							(mid -0.249642 -0.249642)
							(end -0.2794 -0.1778)
						)
						(arc
							(start -0.2794 0.1778)
							(mid -0.249642 0.249642)
							(end -0.1778 0.2794)
						)
						(arc
							(start 0.1778 0.2794)
							(mid 0.249642 0.249642)
							(end 0.2794 0.1778)
						)
						(arc
							(start 0.2794 -0.1778)
							(mid 0.249642 -0.249642)
							(end 0.1778 -0.2794)
						)
					)
					(width 0)
					(fill yes)
				)
			)
		)
	)
	(footprint ""
		(layer "F.Cu")
		(at 364.290102 -164.596318 90)
		(property "Reference" "C295"
			(at 0 0 90)
			(layer "F.SilkS")
			(hide yes)
			(effects
				(font
					(size 1.27 1.27)
				)
			)
		)
		(property "Value" "SCD033U25V2KX-GP"
			(at 1.1811 -2.7051 90)
			(unlocked yes)
			(layer "F.Fab")
			(hide yes)
			(effects
				(font
					(size 1.016 1.016)
					(thickness 0.1524)
				)
			)
		)
		(property "Device Type" "C402H22"
			(at 1.1811 -4.2291 90)
			(unlocked yes)
			(layer "F.Fab")
			(hide yes)
			(effects
				(font
					(size 1.016 1.016)
					(thickness 0.1524)
				)
			)
		)
		(duplicate_pad_numbers_are_jumpers no)
		(fp_rect
			(start -0.4318 0.9525)
			(end 0.4318 -0.9525)
			(stroke
				(width 0)
				(type default)
			)
			(fill no)
			(layer "F.CrtYd")
		)
		(fp_rect
			(start -0.4318 0.9525)
			(end 0.4318 -0.9525)
			(stroke
				(width 0)
				(type default)
			)
			(fill no)
			(layer "F.Fab")
		)
		(pad "1" smd custom
			(at 0 -0.4445 90)
			(size 0.1524 0.1524)
			(layers "F.Cu" "F.Mask" "F.Paste")
			(net "SW_HDD_P19")
			(options
				(clearance outline)
				(anchor circle)
			)
			(primitives
				(gr_poly
					(pts
						(arc
							(start 0.3048 -0.2032)
							(mid 0.275042 -0.275042)
							(end 0.2032 -0.3048)
						)
						(arc
							(start -0.2032 -0.3048)
							(mid -0.275042 -0.275042)
							(end -0.3048 -0.2032)
						)
						(arc
							(start -0.3048 0.2032)
							(mid -0.275042 0.275042)
							(end -0.2032 0.3048)
						)
						(arc
							(start 0.2032 0.3048)
							(mid 0.275042 0.275042)
							(end 0.3048 0.2032)
						)
					)
					(width 0)
					(fill yes)
				)
			)
		)
		(pad "2" smd custom
			(at 0 0.4445 90)
			(size 0.1524 0.1524)
			(layers "F.Cu" "F.Mask" "F.Paste")
			(net "GND")
			(options
				(clearance outline)
				(anchor circle)
			)
			(primitives
				(gr_poly
					(pts
						(arc
							(start 0.3048 -0.2032)
							(mid 0.275042 -0.275042)
							(end 0.2032 -0.3048)
						)
						(arc
							(start -0.2032 -0.3048)
							(mid -0.275042 -0.275042)
							(end -0.3048 -0.2032)
						)
						(arc
							(start -0.3048 0.2032)
							(mid -0.275042 0.275042)
							(end -0.2032 0.3048)
						)
						(arc
							(start 0.2032 0.3048)
							(mid 0.275042 0.275042)
							(end 0.3048 0.2032)
						)
					)
					(width 0)
					(fill yes)
				)
			)
		)
	)
	(footprint ""
		(layer "F.Cu")
		(at 35.5854 -298.704)
		(property "Reference" "TP182"
			(at 0 0 0)
			(layer "F.SilkS")
			(hide yes)
			(effects
				(font
					(size 1.27 1.27)
				)
			)
		)
		(property "Value" "TPAD32-GP"
			(at -0.0508 -1.6764 0)
			(unlocked yes)
			(layer "F.Fab")
			(hide yes)
			(effects
				(font
					(size 1.016 1.016)
					(thickness 0.1524)
				)
			)
		)
		(property "Device Type" "TPAD32"
			(at -0.0508 -3.2004 0)
			(unlocked yes)
			(layer "F.Fab")
			(hide yes)
			(effects
				(font
					(size 1.016 1.016)
					(thickness 0.1524)
				)
			)
		)
		(duplicate_pad_numbers_are_jumpers no)
		(fp_poly
			(pts
				(arc
					(start 0.4064 0)
					(mid -0.4064 0)
					(end 0.4064 0)
				)
			)
			(stroke
				(width 0)
				(type default)
			)
			(fill no)
			(layer "F.CrtYd")
		)
		(fp_poly
			(pts
				(arc
					(start 0.7112 0)
					(mid -0.7112 0)
					(end 0.7112 0)
				)
			)
			(stroke
				(width 0)
				(type default)
			)
			(fill no)
			(layer "F.Fab")
		)
		(pad "1" smd circle
			(at 0 0)
			(size 0.8128 0.8128)
			(layers "F.Cu" "F.Mask" "F.Paste")
			(net "ACT_HDD_0")
		)
	)
)
